(kicad_pcb
	(version 20260206)
	(generator "pcbnew")
	(generator_version "10.0")
	(general
		(thickness 1.6)
		(legacy_teardrops no)
	)
	(paper "A4")
	(title_block
		(title "pdpb — Lightning_PDPB_BRD.brd")
		(comment 1 "Lightning (Wiwynn / Facebook NVMe JBOF) / footprints 409-415 of 1140")
	)
	(layers
		(0 "F.Cu" signal "TOP")
		(4 "In1.Cu" signal "L2GND")
		(6 "In2.Cu" signal "L3")
		(8 "In3.Cu" signal "L4VCC")
		(10 "In4.Cu" signal "L5VCC")
		(12 "In5.Cu" signal "L6")
		(14 "In6.Cu" signal "L7GND")
		(2 "B.Cu" signal "BOTTOM")
		(9 "F.Adhes" user "F.Adhesive")
		(11 "B.Adhes" user "B.Adhesive")
		(13 "F.Paste" user "Package Geometry/Pastemask Top")
		(15 "B.Paste" user "Package Geometry/Pastemask Bottom")
		(5 "F.SilkS" user "Ref Des/Silkscreen Top")
		(7 "B.SilkS" user "Ref Des/Silkscreen Bottom")
		(1 "F.Mask" user "Board Geometry/Soldermask Top")
		(3 "B.Mask" user "Board Geometry/Soldermask Bottom")
		(17 "Dwgs.User" user "User.Drawings")
		(19 "Cmts.User" user "User.Comments")
		(21 "Eco1.User" user "User.Eco1")
		(23 "Eco2.User" user "User.Eco2")
		(25 "Edge.Cuts" user "Board Geometry/Outline")
		(27 "Margin" user)
		(31 "F.CrtYd" user "Package Geometry/Place Bound Top")
		(29 "B.CrtYd" user "Package Geometry/Place Bound Bottom")
		(35 "F.Fab" user "Ref Des/Assembly Top")
		(33 "B.Fab" user "Ref Des/Assembly Bottom")
	)
	(footprint ""
		(layer "F.Cu")
		(at 12.192 -478.155 180)
		(property "Reference" "R9036"
			(at 0 0 180)
			(layer "F.SilkS")
			(hide yes)
			(effects
				(font
					(size 1.27 1.27)
				)
			)
		)
		(property "Value" "0R2J-2-GP"
			(at 0.064008 -3.993896 180)
			(unlocked yes)
			(layer "F.Fab")
			(hide yes)
			(effects
				(font
					(size 1.016 1.016)
					(thickness 0.1524)
				)
			)
		)
		(property "Device Type" "R402H16"
			(at 0.064008 -5.517896 180)
			(unlocked yes)
			(layer "F.Fab")
			(hide yes)
			(effects
				(font
					(size 1.016 1.016)
					(thickness 0.1524)
				)
			)
		)
		(duplicate_pad_numbers_are_jumpers no)
		(fp_line
			(start 0.508 -0.9398)
			(end -0.508 -0.9398)
			(stroke
				(width 0.1524)
				(type default)
			)
			(layer "F.SilkS")
		)
		(fp_line
			(start -0.508 -0.9398)
			(end -0.508 0.9398)
			(stroke
				(width 0.1524)
				(type default)
			)
			(layer "F.SilkS")
		)
		(fp_rect
			(start -0.508 0.9398)
			(end 0.508 -0.9398)
			(stroke
				(width 0)
				(type default)
			)
			(fill no)
			(layer "F.CrtYd")
		)
		(fp_rect
			(start -0.508 0.9398)
			(end 0.508 -0.9398)
			(stroke
				(width 0)
				(type default)
			)
			(fill no)
			(layer "F.Fab")
		)
		(pad "1" smd custom
			(at 0 -0.4445 180)
			(size 0.1397 0.1397)
			(layers "F.Cu" "F.Mask" "F.Paste")
			(net "SELF_TRAY_PRESENT_R")
			(options
				(clearance outline)
				(anchor circle)
			)
			(primitives
				(gr_poly
					(pts
						(arc
							(start -0.1778 -0.2794)
							(mid -0.249642 -0.249642)
							(end -0.2794 -0.1778)
						)
						(arc
							(start -0.2794 0.1778)
							(mid -0.249642 0.249642)
							(end -0.1778 0.2794)
						)
						(arc
							(start 0.1778 0.2794)
							(mid 0.249642 0.249642)
							(end 0.2794 0.1778)
						)
						(arc
							(start 0.2794 -0.1778)
							(mid 0.249642 -0.249642)
							(end 0.1778 -0.2794)
						)
					)
					(width 0)
					(fill yes)
				)
			)
		)
		(pad "2" smd custom
			(at 0 0.4445 180)
			(size 0.1397 0.1397)
			(layers "F.Cu" "F.Mask" "F.Paste")
			(net "SELF_TRAY_PRESENT")
			(options
				(clearance outline)
				(anchor circle)
			)
			(primitives
				(gr_poly
					(pts
						(arc
							(start -0.1778 -0.2794)
							(mid -0.249642 -0.249642)
							(end -0.2794 -0.1778)
						)
						(arc
							(start -0.2794 0.1778)
							(mid -0.249642 0.249642)
							(end -0.1778 0.2794)
						)
						(arc
							(start 0.1778 0.2794)
							(mid 0.249642 0.249642)
							(end 0.2794 0.1778)
						)
						(arc
							(start 0.2794 -0.1778)
							(mid 0.249642 -0.249642)
							(end 0.1778 -0.2794)
						)
					)
					(width 0)
					(fill yes)
				)
			)
		)
	)
	(footprint ""
		(layer "F.Cu")
		(at 207.391 -403.225 180)
		(property "Reference" "R9499"
			(at 0 0 180)
			(layer "F.SilkS")
			(hide yes)
			(effects
				(font
					(size 1.27 1.27)
				)
			)
		)
		(property "Value" "4K7R2J-2-GP"
			(at 0.064008 -3.993896 180)
			(unlocked yes)
			(layer "F.Fab")
			(hide yes)
			(effects
				(font
					(size 1.016 1.016)
					(thickness 0.1524)
				)
			)
		)
		(property "Device Type" "R402H16"
			(at 0.064008 -5.517896 180)
			(unlocked yes)
			(layer "F.Fab")
			(hide yes)
			(effects
				(font
					(size 1.016 1.016)
					(thickness 0.1524)
				)
			)
		)
		(duplicate_pad_numbers_are_jumpers no)
		(fp_line
			(start 0.508 -0.9398)
			(end -0.508 -0.9398)
			(stroke
				(width 0.1524)
				(type default)
			)
			(layer "F.SilkS")
		)
		(fp_line
			(start -0.508 -0.9398)
			(end -0.508 0.9398)
			(stroke
				(width 0.1524)
				(type default)
			)
			(layer "F.SilkS")
		)
		(fp_rect
			(start -0.508 0.9398)
			(end 0.508 -0.9398)
			(stroke
				(width 0)
				(type default)
			)
			(fill no)
			(layer "F.CrtYd")
		)
		(fp_rect
			(start -0.508 0.9398)
			(end 0.508 -0.9398)
			(stroke
				(width 0)
				(type default)
			)
			(fill no)
			(layer "F.Fab")
		)
		(pad "1" smd custom
			(at 0 -0.4445 180)
			(size 0.1397 0.1397)
			(layers "F.Cu" "F.Mask" "F.Paste")
			(net "P3V3")
			(options
				(clearance outline)
				(anchor circle)
			)
			(primitives
				(gr_poly
					(pts
						(arc
							(start -0.1778 -0.2794)
							(mid -0.249642 -0.249642)
							(end -0.2794 -0.1778)
						)
						(arc
							(start -0.2794 0.1778)
							(mid -0.249642 0.249642)
							(end -0.1778 0.2794)
						)
						(arc
							(start 0.1778 0.2794)
							(mid 0.249642 0.249642)
							(end 0.2794 0.1778)
						)
						(arc
							(start 0.2794 -0.1778)
							(mid 0.249642 -0.249642)
							(end 0.1778 -0.2794)
						)
					)
					(width 0)
					(fill yes)
				)
			)
		)
		(pad "2" smd custom
			(at 0 0.4445 180)
			(size 0.1397 0.1397)
			(layers "F.Cu" "F.Mask" "F.Paste")
			(net "SSD1_PWREN")
			(options
				(clearance outline)
				(anchor circle)
			)
			(primitives
				(gr_poly
					(pts
						(arc
							(start -0.1778 -0.2794)
							(mid -0.249642 -0.249642)
							(end -0.2794 -0.1778)
						)
						(arc
							(start -0.2794 0.1778)
							(mid -0.249642 0.249642)
							(end -0.1778 0.2794)
						)
						(arc
							(start 0.1778 0.2794)
							(mid 0.249642 0.249642)
							(end 0.2794 0.1778)
						)
						(arc
							(start 0.2794 -0.1778)
							(mid 0.249642 -0.249642)
							(end 0.1778 -0.2794)
						)
					)
					(width 0)
					(fill yes)
				)
			)
		)
	)
	(footprint ""
		(layer "F.Cu")
		(at 92.837 -19.431 -90)
		(property "Reference" "C357"
			(at 0 0 270)
			(layer "F.SilkS")
			(hide yes)
			(effects
				(font
					(size 1.27 1.27)
				)
			)
		)
		(property "Value" "SCD1U16V2KX-3GP"
			(at 1.1811 -2.7051 270)
			(unlocked yes)
			(layer "F.Fab")
			(hide yes)
			(effects
				(font
					(size 1.016 1.016)
					(thickness 0.1524)
				)
			)
		)
		(property "Device Type" "C402H22"
			(at 1.1811 -4.2291 270)
			(unlocked yes)
			(layer "F.Fab")
			(hide yes)
			(effects
				(font
					(size 1.016 1.016)
					(thickness 0.1524)
				)
			)
		)
		(duplicate_pad_numbers_are_jumpers no)
		(fp_rect
			(start -0.4318 0.9525)
			(end 0.4318 -0.9525)
			(stroke
				(width 0)
				(type default)
			)
			(fill no)
			(layer "F.CrtYd")
		)
		(fp_rect
			(start -0.4318 0.9525)
			(end 0.4318 -0.9525)
			(stroke
				(width 0)
				(type default)
			)
			(fill no)
			(layer "F.Fab")
		)
		(pad "1" smd custom
			(at 0 -0.4445 270)
			(size 0.1524 0.1524)
			(layers "F.Cu" "F.Mask" "F.Paste")
			(net "P12V_SENSE")
			(options
				(clearance outline)
				(anchor circle)
			)
			(primitives
				(gr_poly
					(pts
						(arc
							(start 0.3048 -0.2032)
							(mid 0.275042 -0.275042)
							(end 0.2032 -0.3048)
						)
						(arc
							(start -0.2032 -0.3048)
							(mid -0.275042 -0.275042)
							(end -0.3048 -0.2032)
						)
						(arc
							(start -0.3048 0.2032)
							(mid -0.275042 0.275042)
							(end -0.2032 0.3048)
						)
						(arc
							(start 0.2032 0.3048)
							(mid 0.275042 0.275042)
							(end 0.3048 0.2032)
						)
					)
					(width 0)
					(fill yes)
				)
			)
		)
		(pad "2" smd custom
			(at 0 0.4445 270)
			(size 0.1524 0.1524)
			(layers "F.Cu" "F.Mask" "F.Paste")
			(net "GND")
			(options
				(clearance outline)
				(anchor circle)
			)
			(primitives
				(gr_poly
					(pts
						(arc
							(start 0.3048 -0.2032)
							(mid 0.275042 -0.275042)
							(end 0.2032 -0.3048)
						)
						(arc
							(start -0.2032 -0.3048)
							(mid -0.275042 -0.275042)
							(end -0.3048 -0.2032)
						)
						(arc
							(start -0.3048 0.2032)
							(mid -0.275042 0.275042)
							(end -0.2032 0.3048)
						)
						(arc
							(start 0.2032 0.3048)
							(mid 0.275042 0.275042)
							(end 0.3048 0.2032)
						)
					)
					(width 0)
					(fill yes)
				)
			)
		)
	)
	(footprint ""
		(layer "F.Cu")
		(at 108.966 -208.026)
		(property "Reference" "R9490"
			(at 0 0 0)
			(layer "F.SilkS")
			(hide yes)
			(effects
				(font
					(size 1.27 1.27)
				)
			)
		)
		(property "Value" "4K7R2J-2-GP"
			(at 0.064008 -3.993896 0)
			(unlocked yes)
			(layer "F.Fab")
			(hide yes)
			(effects
				(font
					(size 1.016 1.016)
					(thickness 0.1524)
				)
			)
		)
		(property "Device Type" "R402H16"
			(at 0.064008 -5.517896 0)
			(unlocked yes)
			(layer "F.Fab")
			(hide yes)
			(effects
				(font
					(size 1.016 1.016)
					(thickness 0.1524)
				)
			)
		)
		(duplicate_pad_numbers_are_jumpers no)
		(fp_line
			(start -0.508 -0.9398)
			(end -0.508 0.9398)
			(stroke
				(width 0.1524)
				(type default)
			)
			(layer "F.SilkS")
		)
		(fp_line
			(start 0.508 -0.9398)
			(end -0.508 -0.9398)
			(stroke
				(width 0.1524)
				(type default)
			)
			(layer "F.SilkS")
		)
		(fp_rect
			(start -0.508 0.9398)
			(end 0.508 -0.9398)
			(stroke
				(width 0)
				(type default)
			)
			(fill no)
			(layer "F.CrtYd")
		)
		(fp_rect
			(start -0.508 0.9398)
			(end 0.508 -0.9398)
			(stroke
				(width 0)
				(type default)
			)
			(fill no)
			(layer "F.Fab")
		)
		(pad "1" smd custom
			(at 0 -0.4445)
			(size 0.1397 0.1397)
			(layers "F.Cu" "F.Mask" "F.Paste")
			(net "P3V3")
			(options
				(clearance outline)
				(anchor circle)
			)
			(primitives
				(gr_poly
					(pts
						(arc
							(start -0.1778 -0.2794)
							(mid -0.249642 -0.249642)
							(end -0.2794 -0.1778)
						)
						(arc
							(start -0.2794 0.1778)
							(mid -0.249642 0.249642)
							(end -0.1778 0.2794)
						)
						(arc
							(start 0.1778 0.2794)
							(mid 0.249642 0.249642)
							(end 0.2794 0.1778)
						)
						(arc
							(start 0.2794 -0.1778)
							(mid 0.249642 -0.249642)
							(end 0.1778 -0.2794)
						)
					)
					(width 0)
					(fill yes)
				)
			)
		)
		(pad "2" smd custom
			(at 0 0.4445)
			(size 0.1397 0.1397)
			(layers "F.Cu" "F.Mask" "F.Paste")
			(net "SSD3_CLK0_OE_N")
			(options
				(clearance outline)
				(anchor circle)
			)
			(primitives
				(gr_poly
					(pts
						(arc
							(start -0.1778 -0.2794)
							(mid -0.249642 -0.249642)
							(end -0.2794 -0.1778)
						)
						(arc
							(start -0.2794 0.1778)
							(mid -0.249642 0.249642)
							(end -0.1778 0.2794)
						)
						(arc
							(start 0.1778 0.2794)
							(mid 0.249642 0.249642)
							(end 0.2794 0.1778)
						)
						(arc
							(start 0.2794 -0.1778)
							(mid 0.249642 -0.249642)
							(end 0.1778 -0.2794)
						)
					)
					(width 0)
					(fill yes)
				)
			)
		)
	)
	(footprint ""
		(layer "F.Cu")
		(at 232.029 -430.53 -90)
		(property "Reference" "PR9090"
			(at 0 0 270)
			(layer "F.SilkS")
			(hide yes)
			(effects
				(font
					(size 1.27 1.27)
				)
			)
		)
		(property "Value" "33KR2F-2-GP"
			(at 0.064008 -3.993896 270)
			(unlocked yes)
			(layer "F.Fab")
			(hide yes)
			(effects
				(font
					(size 1.016 1.016)
					(thickness 0.1524)
				)
			)
		)
		(property "Device Type" "R402H16"
			(at 0.064008 -5.517896 270)
			(unlocked yes)
			(layer "F.Fab")
			(hide yes)
			(effects
				(font
					(size 1.016 1.016)
					(thickness 0.1524)
				)
			)
		)
		(duplicate_pad_numbers_are_jumpers no)
		(fp_line
			(start -0.508 -0.9398)
			(end -0.508 0.9398)
			(stroke
				(width 0.1524)
				(type default)
			)
			(layer "F.SilkS")
		)
		(fp_line
			(start 0.508 -0.9398)
			(end -0.508 -0.9398)
			(stroke
				(width 0.1524)
				(type default)
			)
			(layer "F.SilkS")
		)
		(fp_rect
			(start -0.508 0.9398)
			(end 0.508 -0.9398)
			(stroke
				(width 0)
				(type default)
			)
			(fill no)
			(layer "F.CrtYd")
		)
		(fp_rect
			(start -0.508 0.9398)
			(end 0.508 -0.9398)
			(stroke
				(width 0)
				(type default)
			)
			(fill no)
			(layer "F.Fab")
		)
		(pad "1" smd custom
			(at 0 -0.4445 270)
			(size 0.1397 0.1397)
			(layers "F.Cu" "F.Mask" "F.Paste")
			(net "P3V3_CC_R")
			(options
				(clearance outline)
				(anchor circle)
			)
			(primitives
				(gr_poly
					(pts
						(arc
							(start -0.1778 -0.2794)
							(mid -0.249642 -0.249642)
							(end -0.2794 -0.1778)
						)
						(arc
							(start -0.2794 0.1778)
							(mid -0.249642 0.249642)
							(end -0.1778 0.2794)
						)
						(arc
							(start 0.1778 0.2794)
							(mid 0.249642 0.249642)
							(end 0.2794 0.1778)
						)
						(arc
							(start 0.2794 -0.1778)
							(mid 0.249642 -0.249642)
							(end 0.1778 -0.2794)
						)
					)
					(width 0)
					(fill yes)
				)
			)
		)
		(pad "2" smd custom
			(at 0 0.4445 270)
			(size 0.1397 0.1397)
			(layers "F.Cu" "F.Mask" "F.Paste")
			(net "P3V3_VFB")
			(options
				(clearance outline)
				(anchor circle)
			)
			(primitives
				(gr_poly
					(pts
						(arc
							(start -0.1778 -0.2794)
							(mid -0.249642 -0.249642)
							(end -0.2794 -0.1778)
						)
						(arc
							(start -0.2794 0.1778)
							(mid -0.249642 0.249642)
							(end -0.1778 0.2794)
						)
						(arc
							(start 0.1778 0.2794)
							(mid 0.249642 0.249642)
							(end 0.2794 0.1778)
						)
						(arc
							(start 0.2794 -0.1778)
							(mid 0.249642 -0.249642)
							(end 0.1778 -0.2794)
						)
					)
					(width 0)
					(fill yes)
				)
			)
		)
	)
	(footprint ""
		(layer "F.Cu")
		(at 35.0012 -189.3824)
		(property "Reference" "PC1216"
			(at 0 0 0)
			(layer "F.SilkS")
			(hide yes)
			(effects
				(font
					(size 1.27 1.27)
				)
			)
		)
		(property "Value" "SC22U25V6KX-GP-U"
			(at -2.860802 -5.279644 0)
			(unlocked yes)
			(layer "F.Fab")
			(hide yes)
			(effects
				(font
					(size 1.016 1.016)
					(thickness 0.1524)
				)
			)
		)
		(property "Device Type" "C1206-TO0D3H75"
			(at -2.860802 -6.803644 0)
			(unlocked yes)
			(layer "F.Fab")
			(hide yes)
			(effects
				(font
					(size 1.016 1.016)
					(thickness 0.1524)
				)
			)
		)
		(duplicate_pad_numbers_are_jumpers no)
		(fp_line
			(start -1.3081 -2.3749)
			(end 1.3081 -2.3749)
			(stroke
				(width 0.1524)
				(type default)
			)
			(layer "F.SilkS")
		)
		(fp_line
			(start -1.3081 2.3749)
			(end -1.3081 -2.3749)
			(stroke
				(width 0.1524)
				(type default)
			)
			(layer "F.SilkS")
		)
		(fp_line
			(start 1.3081 -2.3749)
			(end 1.3081 2.3749)
			(stroke
				(width 0.1524)
				(type default)
			)
			(layer "F.SilkS")
		)
		(fp_line
			(start 1.3081 2.3749)
			(end -1.3081 2.3749)
			(stroke
				(width 0.1524)
				(type default)
			)
			(layer "F.SilkS")
		)
		(fp_rect
			(start -0.8001 1.6002)
			(end 0.8001 -1.6002)
			(stroke
				(width 0)
				(type default)
			)
			(fill no)
			(layer "F.CrtYd")
		)
		(fp_poly
			(pts
				(xy -1.5621 2.4511) (xy -1.5621 1.6002) (xy 0.8001 1.6002) (xy 0.8001 -1.6002) (xy -0.8001 -1.6002)
				(xy -0.8001 1.5875) (xy -1.5621 1.5875) (xy -1.5621 -2.4511) (xy 1.5621 -2.4511) (xy 1.5621 2.4511)
			)
			(stroke
				(width 0)
				(type default)
			)
			(fill no)
			(layer "F.CrtYd")
		)
		(fp_rect
			(start -1.5621 2.4511)
			(end 1.5621 -2.4511)
			(stroke
				(width 0)
				(type default)
			)
			(fill no)
			(layer "F.Fab")
		)
		(pad "1" smd rect
			(at 0 -1.392936)
			(size 2.1082 1.4478)
			(layers "F.Cu" "F.Mask" "F.Paste")
			(net "P12V_SSD8")
		)
		(pad "2" smd rect
			(at 0 1.392936)
			(size 2.1082 1.4478)
			(layers "F.Cu" "F.Mask" "F.Paste")
			(net "GND")
		)
	)
	(footprint ""
		(layer "F.Cu")
		(at 29.845 -115.443 90)
		(property "Reference" "R415"
			(at 0 0 90)
			(layer "F.SilkS")
			(hide yes)
			(effects
				(font
					(size 1.27 1.27)
				)
			)
		)
		(property "Value" "0R2J-2-GP"
			(at 0.064008 -3.993896 90)
			(unlocked yes)
			(layer "F.Fab")
			(hide yes)
			(effects
				(font
					(size 1.016 1.016)
					(thickness 0.1524)
				)
			)
		)
		(property "Device Type" "R402H16"
			(at 0.064008 -5.517896 90)
			(unlocked yes)
			(layer "F.Fab")
			(hide yes)
			(effects
				(font
					(size 1.016 1.016)
					(thickness 0.1524)
				)
			)
		)
		(duplicate_pad_numbers_are_jumpers no)
		(fp_line
			(start 0.508 -0.9398)
			(end -0.508 -0.9398)
			(stroke
				(width 0.1524)
				(type default)
			)
			(layer "F.SilkS")
		)
		(fp_line
			(start -0.508 -0.9398)
			(end -0.508 0.9398)
			(stroke
				(width 0.1524)
				(type default)
			)
			(layer "F.SilkS")
		)
		(fp_rect
			(start -0.508 0.9398)
			(end 0.508 -0.9398)
			(stroke
				(width 0)
				(type default)
			)
			(fill no)
			(layer "F.CrtYd")
		)
		(fp_rect
			(start -0.508 0.9398)
			(end 0.508 -0.9398)
			(stroke
				(width 0)
				(type default)
			)
			(fill no)
			(layer "F.Fab")
		)
		(pad "1" smd custom
			(at 0 -0.4445 90)
			(size 0.1397 0.1397)
			(layers "F.Cu" "F.Mask" "F.Paste")
			(net "SCL_DR13_R")
			(options
				(clearance outline)
				(anchor circle)
			)
			(primitives
				(gr_poly
					(pts
						(arc
							(start -0.1778 -0.2794)
							(mid -0.249642 -0.249642)
							(end -0.2794 -0.1778)
						)
						(arc
							(start -0.2794 0.1778)
							(mid -0.249642 0.249642)
							(end -0.1778 0.2794)
						)
						(arc
							(start 0.1778 0.2794)
							(mid 0.249642 0.249642)
							(end 0.2794 0.1778)
						)
						(arc
							(start 0.2794 -0.1778)
							(mid 0.249642 -0.249642)
							(end 0.1778 -0.2794)
						)
					)
					(width 0)
					(fill yes)
				)
			)
		)
		(pad "2" smd custom
			(at 0 0.4445 90)
			(size 0.1397 0.1397)
			(layers "F.Cu" "F.Mask" "F.Paste")
			(net "SCL_DR13")
			(options
				(clearance outline)
				(anchor circle)
			)
			(primitives
				(gr_poly
					(pts
						(arc
							(start -0.1778 -0.2794)
							(mid -0.249642 -0.249642)
							(end -0.2794 -0.1778)
						)
						(arc
							(start -0.2794 0.1778)
							(mid -0.249642 0.249642)
							(end -0.1778 0.2794)
						)
						(arc
							(start 0.1778 0.2794)
							(mid 0.249642 0.249642)
							(end 0.2794 0.1778)
						)
						(arc
							(start 0.2794 -0.1778)
							(mid 0.249642 -0.249642)
							(end 0.1778 -0.2794)
						)
					)
					(width 0)
					(fill yes)
				)
			)
		)
	)
)
